(kicad_pcb
	(version 20260206)
	(generator "pcbnew")
	(generator_version "10.0")
	(general
		(thickness 1.6)
		(legacy_teardrops no)
	)
	(paper "A4")
	(title_block
		(title "Bryce Canyon_R.DPB_16317-1_OCP.brd")
		(comment 1 "Bryce Canyon / footprints 1756-1762 of 2099")
	)
	(layers
		(0 "F.Cu" signal "TOP")
		(4 "In1.Cu" signal "L2GND")
		(6 "In2.Cu" signal "L3")
		(8 "In3.Cu" signal "L4VCC")
		(10 "In4.Cu" signal "L5VCC")
		(12 "In5.Cu" signal "L6")
		(14 "In6.Cu" signal "L7GND")
		(2 "B.Cu" signal "BOTTOM")
		(9 "F.Adhes" user "F.Adhesive")
		(11 "B.Adhes" user "B.Adhesive")
		(13 "F.Paste" user "Package Geometry/Pastemask Top")
		(15 "B.Paste" user "Package Geometry/Pastemask Bottom")
		(5 "F.SilkS" user "Ref Des/Silkscreen Top")
		(7 "B.SilkS" user "Ref Des/Silkscreen Bottom")
		(1 "F.Mask" user "Board Geometry/Soldermask Top")
		(3 "B.Mask" user "Board Geometry/Soldermask Bottom")
		(17 "Dwgs.User" user "User.Drawings")
		(19 "Cmts.User" user "User.Comments")
		(21 "Eco1.User" user "User.Eco1")
		(23 "Eco2.User" user "User.Eco2")
		(25 "Edge.Cuts" user "Board Geometry/Outline")
		(27 "Margin" user)
		(31 "F.CrtYd" user "Package Geometry/Place Bound Top")
		(29 "B.CrtYd" user "Package Geometry/Place Bound Bottom")
		(35 "F.Fab" user "Ref Des/Assembly Top")
		(33 "B.Fab" user "Ref Des/Assembly Bottom")
	)
	(footprint ""
		(layer "F.Cu")
		(at 378.968 -214.249)
		(property "Reference" "R333"
			(at 0 0 0)
			(layer "F.SilkS")
			(hide yes)
			(effects
				(font
					(size 1.27 1.27)
				)
			)
		)
		(property "Value" "91R3F-1-GP"
			(at -0.0254 -2.5146 0)
			(unlocked yes)
			(layer "F.Fab")
			(hide yes)
			(effects
				(font
					(size 1.016 1.016)
					(thickness 0.1524)
				)
			)
		)
		(property "Device Type" "R603H22"
			(at -0.0254 -4.0386 0)
			(unlocked yes)
			(layer "F.Fab")
			(hide yes)
			(effects
				(font
					(size 1.016 1.016)
					(thickness 0.1524)
				)
			)
		)
		(duplicate_pad_numbers_are_jumpers no)
		(fp_line
			(start -0.4826 0)
			(end -0.2032 0)
			(stroke
				(width 0.2032)
				(type default)
			)
			(layer "F.SilkS")
		)
		(fp_line
			(start 0.2032 0)
			(end 0.4826 0)
			(stroke
				(width 0.2032)
				(type default)
			)
			(layer "F.SilkS")
		)
		(fp_rect
			(start -0.5842 1.3335)
			(end 0.5842 -1.3335)
			(stroke
				(width 0)
				(type default)
			)
			(fill no)
			(layer "F.CrtYd")
		)
		(fp_rect
			(start -0.5842 1.3335)
			(end 0.5842 -1.3335)
			(stroke
				(width 0)
				(type default)
			)
			(fill no)
			(layer "F.Fab")
		)
		(pad "1" smd custom
			(at 0 -0.762)
			(size 0.2159 0.2159)
			(layers "F.Cu" "F.Mask" "F.Paste")
			(net "P5V_B_3")
			(options
				(clearance outline)
				(anchor circle)
			)
			(primitives
				(gr_poly
					(pts
						(arc
							(start -0.3302 -0.4318)
							(mid -0.402042 -0.402042)
							(end -0.4318 -0.3302)
						)
						(arc
							(start -0.4318 0.3302)
							(mid -0.402042 0.402042)
							(end -0.3302 0.4318)
						)
						(arc
							(start 0.3302 0.4318)
							(mid 0.402042 0.402042)
							(end 0.4318 0.3302)
						)
						(arc
							(start 0.4318 -0.3302)
							(mid 0.402042 -0.402042)
							(end 0.3302 -0.4318)
						)
					)
					(width 0)
					(fill yes)
				)
			)
		)
		(pad "2" smd custom
			(at 0 0.762)
			(size 0.2159 0.2159)
			(layers "F.Cu" "F.Mask" "F.Paste")
			(net "DRV_ACT_8")
			(options
				(clearance outline)
				(anchor circle)
			)
			(primitives
				(gr_poly
					(pts
						(arc
							(start -0.3302 -0.4318)
							(mid -0.402042 -0.402042)
							(end -0.4318 -0.3302)
						)
						(arc
							(start -0.4318 0.3302)
							(mid -0.402042 0.402042)
							(end -0.3302 0.4318)
						)
						(arc
							(start 0.3302 0.4318)
							(mid 0.402042 0.402042)
							(end 0.4318 0.3302)
						)
						(arc
							(start 0.4318 -0.3302)
							(mid 0.402042 -0.402042)
							(end 0.3302 -0.4318)
						)
					)
					(width 0)
					(fill yes)
				)
			)
		)
	)
	(footprint ""
		(layer "F.Cu")
		(at 339.743796 -214.860378 90)
		(property "Reference" "Q250"
			(at 0 0 90)
			(layer "F.SilkS")
			(hide yes)
			(effects
				(font
					(size 1.27 1.27)
				)
			)
		)
		(property "Value" "SSM3K324R-GP"
			(at 0.127 -8.9662 90)
			(unlocked yes)
			(layer "F.Fab")
			(hide yes)
			(effects
				(font
					(size 1.016 1.016)
					(thickness 0.1524)
				)
			)
		)
		(property "Device Type" "SOT23DGS2D4H35"
			(at 0.127 -10.4902 90)
			(unlocked yes)
			(layer "F.Fab")
			(hide yes)
			(effects
				(font
					(size 1.016 1.016)
					(thickness 0.1524)
				)
			)
		)
		(duplicate_pad_numbers_are_jumpers no)
		(fp_line
			(start 1.651 -1.778)
			(end -1.651 -1.778)
			(stroke
				(width 0.1524)
				(type default)
			)
			(layer "F.SilkS")
		)
		(fp_line
			(start -1.651 -1.778)
			(end -1.651 1.778)
			(stroke
				(width 0.1524)
				(type default)
			)
			(layer "F.SilkS")
		)
		(fp_line
			(start 1.651 1.778)
			(end 1.651 -1.778)
			(stroke
				(width 0.1524)
				(type default)
			)
			(layer "F.SilkS")
		)
		(fp_line
			(start -1.651 1.778)
			(end 1.651 1.778)
			(stroke
				(width 0.1524)
				(type default)
			)
			(layer "F.SilkS")
		)
		(fp_poly
			(pts
				(xy -1.778 1.8796) (xy -1.778 -1.8796) (xy 1.778 -1.8796) (xy 1.778 1.8796)
			)
			(stroke
				(width 0)
				(type default)
			)
			(fill no)
			(layer "F.CrtYd")
		)
		(fp_poly
			(pts
				(xy -1.778 1.8796) (xy -1.778 -1.8796) (xy 1.778 -1.8796) (xy 1.778 1.8796)
			)
			(stroke
				(width 0)
				(type default)
			)
			(fill no)
			(layer "F.Fab")
		)
		(pad "D" smd custom
			(at 0 -0.9525 90)
			(size 0.1905 0.1905)
			(layers "F.Cu" "F.Mask" "F.Paste")
			(net "DRV_ACT_7_N")
			(options
				(clearance outline)
				(anchor circle)
			)
			(primitives
				(gr_poly
					(pts
						(arc
							(start -0.1778 0.5715)
							(mid -0.321484 0.511984)
							(end -0.381 0.3683)
						)
						(arc
							(start -0.381 -0.3683)
							(mid -0.321484 -0.511984)
							(end -0.1778 -0.5715)
						)
						(arc
							(start 0.1778 -0.5715)
							(mid 0.321484 -0.511984)
							(end 0.381 -0.3683)
						)
						(arc
							(start 0.381 0.3683)
							(mid 0.321484 0.511984)
							(end 0.1778 0.5715)
						)
					)
					(width 0)
					(fill yes)
				)
			)
		)
		(pad "G" smd custom
			(at -0.98425 0.9525 90)
			(size 0.1905 0.1905)
			(layers "F.Cu" "F.Mask" "F.Paste")
			(net "DRIVE_B_7_ACT")
			(options
				(clearance outline)
				(anchor circle)
			)
			(primitives
				(gr_poly
					(pts
						(arc
							(start -0.1778 0.5715)
							(mid -0.321484 0.511984)
							(end -0.381 0.3683)
						)
						(arc
							(start -0.381 -0.3683)
							(mid -0.321484 -0.511984)
							(end -0.1778 -0.5715)
						)
						(arc
							(start 0.1778 -0.5715)
							(mid 0.321484 -0.511984)
							(end 0.381 -0.3683)
						)
						(arc
							(start 0.381 0.3683)
							(mid 0.321484 0.511984)
							(end 0.1778 0.5715)
						)
					)
					(width 0)
					(fill yes)
				)
			)
		)
		(pad "S" smd custom
			(at 0.98425 0.9525 90)
			(size 0.1905 0.1905)
			(layers "F.Cu" "F.Mask" "F.Paste")
			(net "GND")
			(options
				(clearance outline)
				(anchor circle)
			)
			(primitives
				(gr_poly
					(pts
						(arc
							(start -0.1778 0.5715)
							(mid -0.321484 0.511984)
							(end -0.381 0.3683)
						)
						(arc
							(start -0.381 -0.3683)
							(mid -0.321484 -0.511984)
							(end -0.1778 -0.5715)
						)
						(arc
							(start 0.1778 -0.5715)
							(mid 0.321484 -0.511984)
							(end 0.381 -0.3683)
						)
						(arc
							(start 0.381 0.3683)
							(mid 0.321484 0.511984)
							(end 0.1778 0.5715)
						)
					)
					(width 0)
					(fill yes)
				)
			)
		)
	)
	(footprint ""
		(layer "F.Cu")
		(at 175.550068 -180.399944)
		(property "Reference" "LED6"
			(at 0 0 0)
			(layer "F.SilkS")
			(hide yes)
			(effects
				(font
					(size 1.27 1.27)
				)
			)
		)
		(property "Value" "LED-BY-19-GP"
			(at -2.132076 1.414018 0)
			(unlocked yes)
			(layer "F.Fab")
			(hide yes)
			(effects
				(font
					(size 1.016 1.016)
					(thickness 0.1524)
				)
			)
		)
		(property "Device Type" "LED-1615-4PH26"
			(at -2.132076 -0.109982 0)
			(unlocked yes)
			(layer "F.Fab")
			(hide yes)
			(effects
				(font
					(size 1.016 1.016)
					(thickness 0.1524)
				)
			)
		)
		(duplicate_pad_numbers_are_jumpers no)
		(fp_line
			(start -1.2954 0.254)
			(end -1.2954 1.6002)
			(stroke
				(width 0.508)
				(type default)
			)
			(layer "F.SilkS")
		)
		(fp_line
			(start -1.2954 1.6002)
			(end 1.2954 1.6002)
			(stroke
				(width 0.508)
				(type default)
			)
			(layer "F.SilkS")
		)
		(fp_line
			(start -1.1176 -1.4224)
			(end 1.1176 -1.4224)
			(stroke
				(width 0.1524)
				(type default)
			)
			(layer "F.SilkS")
		)
		(fp_line
			(start -1.1176 1.4224)
			(end -1.1176 -1.4224)
			(stroke
				(width 0.1524)
				(type default)
			)
			(layer "F.SilkS")
		)
		(fp_line
			(start 1.1176 -1.4224)
			(end 1.1176 1.4224)
			(stroke
				(width 0.1524)
				(type default)
			)
			(layer "F.SilkS")
		)
		(fp_line
			(start 1.1176 1.4224)
			(end -1.1176 1.4224)
			(stroke
				(width 0.1524)
				(type default)
			)
			(layer "F.SilkS")
		)
		(fp_line
			(start 1.2954 1.6002)
			(end 1.2954 0.254)
			(stroke
				(width 0.508)
				(type default)
			)
			(layer "F.SilkS")
		)
		(fp_rect
			(start -0.7493 0.8001)
			(end 0.7493 -0.8001)
			(stroke
				(width 0)
				(type default)
			)
			(fill no)
			(layer "F.CrtYd")
		)
		(fp_poly
			(pts
				(xy -1.3716 1.6764) (xy -1.3716 -1.6764) (xy 1.3716 -1.6764) (xy 1.3716 0.0635) (xy 0.7493 0.0635)
				(xy 0.7493 -0.8001) (xy -0.7493 -0.8001) (xy -0.7493 0.8001) (xy 0.7493 0.8001) (xy 0.7493 0.0762)
				(xy 1.3716 0.0762) (xy 1.3716 1.6764)
			)
			(stroke
				(width 0)
				(type default)
			)
			(fill no)
			(layer "F.CrtYd")
		)
		(fp_rect
			(start -1.3716 1.6764)
			(end 1.3716 -1.6764)
			(stroke
				(width 0)
				(type default)
			)
			(fill no)
			(layer "F.Fab")
		)
		(pad "1" smd rect
			(at 0.50038 -0.73025)
			(size 0.7112 0.8636)
			(layers "F.Cu" "F.Mask" "F.Paste")
			(net "DRV_ACT_5")
		)
		(pad "2" smd rect
			(at -0.50038 -0.73025)
			(size 0.7112 0.8636)
			(layers "F.Cu" "F.Mask" "F.Paste")
			(net "FLT_HDD5")
		)
		(pad "3" smd rect
			(at 0.50038 0.73025)
			(size 0.7112 0.8636)
			(layers "F.Cu" "F.Mask" "F.Paste")
			(net "DRV_ACT_5_N")
		)
		(pad "4" smd rect
			(at -0.50038 0.73025)
			(size 0.7112 0.8636)
			(layers "F.Cu" "F.Mask" "F.Paste")
			(net "FLT_HDD5_N")
		)
	)
	(footprint ""
		(layer "F.Cu")
		(at 161.544 -147.066 90)
		(property "Reference" "C245"
			(at 0 0 90)
			(layer "F.SilkS")
			(hide yes)
			(effects
				(font
					(size 1.27 1.27)
				)
			)
		)
		(property "Value" "SCD01U50V2KX-1GP"
			(at 1.1811 -2.7051 90)
			(unlocked yes)
			(layer "F.Fab")
			(hide yes)
			(effects
				(font
					(size 1.016 1.016)
					(thickness 0.1524)
				)
			)
		)
		(property "Device Type" "C402H22"
			(at 1.1811 -4.2291 90)
			(unlocked yes)
			(layer "F.Fab")
			(hide yes)
			(effects
				(font
					(size 1.016 1.016)
					(thickness 0.1524)
				)
			)
		)
		(duplicate_pad_numbers_are_jumpers no)
		(fp_rect
			(start -0.4318 0.9525)
			(end 0.4318 -0.9525)
			(stroke
				(width 0)
				(type default)
			)
			(fill no)
			(layer "F.CrtYd")
		)
		(fp_rect
			(start -0.4318 0.9525)
			(end 0.4318 -0.9525)
			(stroke
				(width 0)
				(type default)
			)
			(fill no)
			(layer "F.Fab")
		)
		(pad "1" smd custom
			(at 0 -0.4445 90)
			(size 0.1524 0.1524)
			(layers "F.Cu" "F.Mask" "F.Paste")
			(net "HDD_PRSNT_16")
			(options
				(clearance outline)
				(anchor circle)
			)
			(primitives
				(gr_poly
					(pts
						(arc
							(start 0.3048 -0.2032)
							(mid 0.275042 -0.275042)
							(end 0.2032 -0.3048)
						)
						(arc
							(start -0.2032 -0.3048)
							(mid -0.275042 -0.275042)
							(end -0.3048 -0.2032)
						)
						(arc
							(start -0.3048 0.2032)
							(mid -0.275042 0.275042)
							(end -0.2032 0.3048)
						)
						(arc
							(start 0.2032 0.3048)
							(mid 0.275042 0.275042)
							(end 0.3048 0.2032)
						)
					)
					(width 0)
					(fill yes)
				)
			)
		)
		(pad "2" smd custom
			(at 0 0.4445 90)
			(size 0.1524 0.1524)
			(layers "F.Cu" "F.Mask" "F.Paste")
			(net "GND")
			(options
				(clearance outline)
				(anchor circle)
			)
			(primitives
				(gr_poly
					(pts
						(arc
							(start 0.3048 -0.2032)
							(mid 0.275042 -0.275042)
							(end 0.2032 -0.3048)
						)
						(arc
							(start -0.2032 -0.3048)
							(mid -0.275042 -0.275042)
							(end -0.3048 -0.2032)
						)
						(arc
							(start -0.3048 0.2032)
							(mid -0.275042 0.275042)
							(end -0.2032 0.3048)
						)
						(arc
							(start 0.2032 0.3048)
							(mid 0.275042 0.275042)
							(end 0.3048 0.2032)
						)
					)
					(width 0)
					(fill yes)
				)
			)
		)
	)
	(footprint ""
		(layer "F.Cu")
		(at 97.863914 -154.70505)
		(property "Reference" "TP91"
			(at 0 0 0)
			(layer "F.SilkS")
			(hide yes)
			(effects
				(font
					(size 1.27 1.27)
				)
			)
		)
		(property "Value" "*"
			(at -0.0508 -1.6764 0)
			(unlocked yes)
			(layer "F.Fab")
			(hide yes)
			(effects
				(font
					(size 1.016 1.016)
					(thickness 0.1524)
				)
			)
		)
		(property "Device Type" "TPAD32"
			(at -0.0508 -3.2004 0)
			(unlocked yes)
			(layer "F.Fab")
			(hide yes)
			(effects
				(font
					(size 1.016 1.016)
					(thickness 0.1524)
				)
			)
		)
		(duplicate_pad_numbers_are_jumpers no)
		(fp_poly
			(pts
				(arc
					(start 0.4064 0)
					(mid -0.4064 0)
					(end 0.4064 0)
				)
			)
			(stroke
				(width 0)
				(type default)
			)
			(fill no)
			(layer "F.CrtYd")
		)
		(fp_poly
			(pts
				(arc
					(start 0.7112 0)
					(mid -0.7112 0)
					(end 0.7112 0)
				)
			)
			(stroke
				(width 0)
				(type default)
			)
			(fill no)
			(layer "F.Fab")
		)
		(pad "1" smd circle
			(at 0 0)
			(size 0.8128 0.8128)
			(layers "F.Cu" "F.Mask" "F.Paste")
			(net "ACT_HDD_14")
		)
	)
	(footprint ""
		(layer "F.Cu")
		(at 353.184714 -14.660626 -90)
		(property "Reference" "C432"
			(at 0 0 270)
			(layer "F.SilkS")
			(hide yes)
			(effects
				(font
					(size 1.27 1.27)
				)
			)
		)
		(property "Value" "SCD01U16V1KX-GP"
			(at -2.8321 -1.7399 270)
			(unlocked yes)
			(layer "F.Fab")
			(hide yes)
			(effects
				(font
					(size 1.016 1.016)
					(thickness 0.1524)
				)
			)
		)
		(property "Device Type" "C0201H13"
			(at -2.8321 -3.2639 270)
			(unlocked yes)
			(layer "F.Fab")
			(hide yes)
			(effects
				(font
					(size 1.016 1.016)
					(thickness 0.1524)
				)
			)
		)
		(duplicate_pad_numbers_are_jumpers no)
		(fp_rect
			(start -0.2794 0.6477)
			(end 0.2794 -0.6477)
			(stroke
				(width 0)
				(type default)
			)
			(fill no)
			(layer "F.CrtYd")
		)
		(fp_rect
			(start -0.2794 0.6477)
			(end 0.2794 -0.6477)
			(stroke
				(width 0)
				(type default)
			)
			(fill no)
			(layer "F.Fab")
		)
		(pad "1" smd custom
			(at 0 -0.2794 270)
			(size 0.0762 0.0762)
			(layers "F.Cu" "F.Mask" "F.Paste")
			(net "SAS_HDD_RX_P31")
			(options
				(clearance outline)
				(anchor circle)
			)
			(primitives
				(gr_poly
					(pts
						(arc
							(start 0.1524 -0.127)
							(mid 0.137521 -0.162921)
							(end 0.1016 -0.1778)
						)
						(arc
							(start -0.1016 -0.1778)
							(mid -0.137521 -0.162921)
							(end -0.1524 -0.127)
						)
						(arc
							(start -0.1524 0.127)
							(mid -0.137521 0.162921)
							(end -0.1016 0.1778)
						)
						(arc
							(start 0.1016 0.1778)
							(mid 0.137521 0.162921)
							(end 0.1524 0.127)
						)
					)
					(width 0)
					(fill yes)
				)
			)
		)
		(pad "2" smd custom
			(at 0 0.2794 270)
			(size 0.0762 0.0762)
			(layers "F.Cu" "F.Mask" "F.Paste")
			(net "PHY_SCC_B_TO_DRV_B_31_DP")
			(options
				(clearance outline)
				(anchor circle)
			)
			(primitives
				(gr_poly
					(pts
						(arc
							(start 0.1524 -0.127)
							(mid 0.137521 -0.162921)
							(end 0.1016 -0.1778)
						)
						(arc
							(start -0.1016 -0.1778)
							(mid -0.137521 -0.162921)
							(end -0.1524 -0.127)
						)
						(arc
							(start -0.1524 0.127)
							(mid -0.137521 0.162921)
							(end -0.1016 0.1778)
						)
						(arc
							(start 0.1016 0.1778)
							(mid 0.137521 0.162921)
							(end 0.1524 0.127)
						)
					)
					(width 0)
					(fill yes)
				)
			)
		)
	)
	(footprint ""
		(layer "F.Cu")
		(at 479.384614 -244.660674 -90)
		(property "Reference" "C172"
			(at 0 0 270)
			(layer "F.SilkS")
			(hide yes)
			(effects
				(font
					(size 1.27 1.27)
				)
			)
		)
		(property "Value" "SCD01U16V1KX-GP"
			(at -2.8321 -1.7399 270)
			(unlocked yes)
			(layer "F.Fab")
			(hide yes)
			(effects
				(font
					(size 1.016 1.016)
					(thickness 0.1524)
				)
			)
		)
		(property "Device Type" "C0201H13"
			(at -2.8321 -3.2639 270)
			(unlocked yes)
			(layer "F.Fab")
			(hide yes)
			(effects
				(font
					(size 1.016 1.016)
					(thickness 0.1524)
				)
			)
		)
		(duplicate_pad_numbers_are_jumpers no)
		(fp_rect
			(start -0.2794 0.6477)
			(end 0.2794 -0.6477)
			(stroke
				(width 0)
				(type default)
			)
			(fill no)
			(layer "F.CrtYd")
		)
		(fp_rect
			(start -0.2794 0.6477)
			(end 0.2794 -0.6477)
			(stroke
				(width 0)
				(type default)
			)
			(fill no)
			(layer "F.Fab")
		)
		(pad "1" smd custom
			(at 0 -0.2794 270)
			(size 0.0762 0.0762)
			(layers "F.Cu" "F.Mask" "F.Paste")
			(net "SAS_HDD_RX_P11")
			(options
				(clearance outline)
				(anchor circle)
			)
			(primitives
				(gr_poly
					(pts
						(arc
							(start 0.1524 -0.127)
							(mid 0.137521 -0.162921)
							(end 0.1016 -0.1778)
						)
						(arc
							(start -0.1016 -0.1778)
							(mid -0.137521 -0.162921)
							(end -0.1524 -0.127)
						)
						(arc
							(start -0.1524 0.127)
							(mid -0.137521 0.162921)
							(end -0.1016 0.1778)
						)
						(arc
							(start 0.1016 0.1778)
							(mid 0.137521 0.162921)
							(end 0.1524 0.127)
						)
					)
					(width 0)
					(fill yes)
				)
			)
		)
		(pad "2" smd custom
			(at 0 0.2794 270)
			(size 0.0762 0.0762)
			(layers "F.Cu" "F.Mask" "F.Paste")
			(net "PHY_SCC_B_TO_DRV_B_11_DP")
			(options
				(clearance outline)
				(anchor circle)
			)
			(primitives
				(gr_poly
					(pts
						(arc
							(start 0.1524 -0.127)
							(mid 0.137521 -0.162921)
							(end 0.1016 -0.1778)
						)
						(arc
							(start -0.1016 -0.1778)
							(mid -0.137521 -0.162921)
							(end -0.1524 -0.127)
						)
						(arc
							(start -0.1524 0.127)
							(mid -0.137521 0.162921)
							(end -0.1016 0.1778)
						)
						(arc
							(start 0.1016 0.1778)
							(mid 0.137521 0.162921)
							(end 0.1524 0.127)
						)
					)
					(width 0)
					(fill yes)
				)
			)
		)
	)
)
